# BASEBOARD_FAB2 (Tioga Pass) — schematic netlist excerpt (pin names and nets, part order shuffled) for the footprints in the layout excerpt that follows; sources: Cadence DE-HDL packaged netlist, KiCad conversion of Wiwynn_Tioga_Pass_MB.brd

EU7A5  PXM1310B  IC  pkg QFN  page 218
  BPWM1  = NC
  DNC(0)  = NC
  APWM3  = NC
  APWM2  = VR_PVDDQ_DEF_PWM2
  APWM1  = VR_PVDDQ_DEF_PWM1
  SDA  = SMB_VR_STBY_LVC3_SDA
  SCL  = SMB_VR_STBY_LVC3_SCL
  RESET_N  = NC
  AVRRDY  = PWRGD_PVDDQ_DEF_R
  AVREN  = VR_PVDDQ_DEF_VREN
  VRHOT_N  = IRQ_PVDDQ_DEF_VRHOT_LVT3_R_N
  PINALRT_N  = NC
  MP0  = PU_VR_PVDDQ_DEF_FAULT1
  MP1  = TP_PVDDQ_DEF_MP1
  VCLK  = SVID_CLK_PVDDQ_DEF
  VDIO  = SVID_VDIO_PVDDQ_DEF
  VALRT_N  = SVID_ALERT_PVDDQ_DEF
  MP2  = TP_PVDDQ_DEF_MP2
  AVSEN  = VR_PVDDQ_DEF_AVSP
  AVREF  = VSENSE_PVDDQ_DEF_N
  AIREF1  = VR_PVDDQ_DEF_AIREF1
  AISEN1  = ISENSE_PVDDQ_DEF_PH1_IMON
  AIREF2  = VR_PVDDQ_DEF_AIREF2
  AISEN2  = ISENSE_PVDDQ_DEF_PH2_IMON
  AIREF3  = NC
  AISEN3  = NC
  GND  = GND
  DNC(1)  = NC
  BVSEN  = NC
  BVREF  = NC
  BIREF1  = NC
  BISEN1  = GND
  XADDR2  = VR_PVDDQ_DEF_XADDR2
  BTSEN  = NC
  ATSEN  = A_TSENSE_PVDDQ_DEF
  XADDR1  = VR_PVDDQ_DEF_XADDR1
  VINSEN  = VR_PVDDQ_DEF_VINSEN
  IINSEN  = VR_PVDDQ_DEF_AIINSEN
  VDD  = VR_PVDDQ_DEF_VDD
  VD12  = VR_PVDDQ_DEF_VD12
  THPAD  = GND

(kicad_pcb
	(version 20260206)
	(generator "pcbnew")
	(generator_version "10.0")
	(general
		(thickness 1.6)
		(legacy_teardrops no)
	)
	(paper "A4")
	(title_block
		(title "Wiwynn_Tioga_Pass_MB.brd")
		(comment 1 "Tioga Pass / footprint 1253 of 4770 (EU7A5), pads 1-17 of 41")
	)
	(layers
		(0 "F.Cu" signal "TOP")
		(4 "In1.Cu" signal "L2GND")
		(6 "In2.Cu" signal "L3")
		(8 "In3.Cu" signal "L4GND")
		(10 "In4.Cu" signal "L5")
		(12 "In5.Cu" signal "L6GND")
		(14 "In6.Cu" signal "L7VCC")
		(16 "In7.Cu" signal "L8VCC")
		(18 "In8.Cu" signal "L9GND")
		(20 "In9.Cu" signal "L10")
		(22 "In10.Cu" signal "L11GND")
		(24 "In11.Cu" signal "L12")
		(26 "In12.Cu" signal "L13GND")
		(2 "B.Cu" signal "BOTTOM")
		(9 "F.Adhes" user "F.Adhesive")
		(11 "B.Adhes" user "B.Adhesive")
		(13 "F.Paste" user "Package Geometry/Pastemask Top")
		(15 "B.Paste" user "Package Geometry/Pastemask Bottom")
		(5 "F.SilkS" user "Ref Des/Silkscreen Top")
		(7 "B.SilkS" user "Ref Des/Silkscreen Bottom")
		(1 "F.Mask" user "Board Geometry/Soldermask Top")
		(3 "B.Mask" user "Board Geometry/Soldermask Bottom")
		(17 "Dwgs.User" user "User.Drawings")
		(19 "Cmts.User" user "User.Comments")
		(21 "Eco1.User" user "User.Eco1")
		(23 "Eco2.User" user "User.Eco2")
		(25 "Edge.Cuts" user "Board Geometry/Outline")
		(27 "Margin" user)
		(31 "F.CrtYd" user "Package Geometry/Place Bound Top")
		(29 "B.CrtYd" user "Package Geometry/Place Bound Bottom")
		(35 "F.Fab" user "Ref Des/Assembly Top")
		(33 "B.Fab" user "Ref Des/Assembly Bottom")
	)
	(footprint ""
		(layer "F.Cu")
		(at 359.29824 -138.16457 90)
		(property "Reference" "EU7A5"
			(at -1.51257 -3.29057 90)
			(unlocked yes)
			(layer "F.SilkS")
			(effects
				(font
					(size 0.7874 0.5842)
					(thickness 0.1524)
				)
				(justify left)
			)
		)
		(property "Value" ""
			(at 0 0 90)
			(layer "F.Fab")
			(effects
				(font
					(size 1.27 1.27)
				)
			)
		)
		(duplicate_pad_numbers_are_jumpers no)
		(pad "1" smd custom
			(at -2.4511 -1.800098 90)
			(size 0.0508 0.0508)
			(layers "F.Cu" "F.Mask" "F.Paste")
			(net "Net_283")
			(options
				(clearance outline)
				(anchor circle)
			)
			(primitives
				(gr_poly
					(pts
						(arc
							(start 0.254 -0.1016)
							(mid 0.3556 0)
							(end 0.254 0.1016)
						)
						(xy -0.3556 0.1016) (xy -0.3556 -0.1016)
					)
					(width 0)
					(fill yes)
				)
			)
		)
		(pad "2" smd custom
			(at -2.4511 -1.400048 90)
			(size 0.0508 0.0508)
			(layers "F.Cu" "F.Mask" "F.Paste")
			(net "Net_347")
			(options
				(clearance outline)
				(anchor circle)
			)
			(primitives
				(gr_poly
					(pts
						(arc
							(start 0.254 -0.1016)
							(mid 0.3556 0)
							(end 0.254 0.1016)
						)
						(xy -0.3556 0.1016) (xy -0.3556 -0.1016)
					)
					(width 0)
					(fill yes)
				)
			)
		)
		(pad "3" smd custom
			(at -2.4511 -0.999998 90)
			(size 0.0508 0.0508)
			(layers "F.Cu" "F.Mask" "F.Paste")
			(net "Net_245")
			(options
				(clearance outline)
				(anchor circle)
			)
			(primitives
				(gr_poly
					(pts
						(arc
							(start 0.254 -0.1016)
							(mid 0.3556 0)
							(end 0.254 0.1016)
						)
						(xy -0.3556 0.1016) (xy -0.3556 -0.1016)
					)
					(width 0)
					(fill yes)
				)
			)
		)
		(pad "4" smd custom
			(at -2.4511 -0.599948 90)
			(size 0.0508 0.0508)
			(layers "F.Cu" "F.Mask" "F.Paste")
			(net "VR_PVDDQ_DEF_PWM2")
			(options
				(clearance outline)
				(anchor circle)
			)
			(primitives
				(gr_poly
					(pts
						(arc
							(start 0.254 -0.1016)
							(mid 0.3556 0)
							(end 0.254 0.1016)
						)
						(xy -0.3556 0.1016) (xy -0.3556 -0.1016)
					)
					(width 0)
					(fill yes)
				)
			)
		)
		(pad "5" smd custom
			(at -2.4511 -0.199898 90)
			(size 0.0508 0.0508)
			(layers "F.Cu" "F.Mask" "F.Paste")
			(net "VR_PVDDQ_DEF_PWM1")
			(options
				(clearance outline)
				(anchor circle)
			)
			(primitives
				(gr_poly
					(pts
						(arc
							(start 0.254 -0.1016)
							(mid 0.3556 0)
							(end 0.254 0.1016)
						)
						(xy -0.3556 0.1016) (xy -0.3556 -0.1016)
					)
					(width 0)
					(fill yes)
				)
			)
		)
		(pad "6" smd custom
			(at -2.4511 0.199898 90)
			(size 0.0508 0.0508)
			(layers "F.Cu" "F.Mask" "F.Paste")
			(net "SMB_VR_STBY_LVC3_SDA")
			(options
				(clearance outline)
				(anchor circle)
			)
			(primitives
				(gr_poly
					(pts
						(arc
							(start 0.254 -0.1016)
							(mid 0.3556 0)
							(end 0.254 0.1016)
						)
						(xy -0.3556 0.1016) (xy -0.3556 -0.1016)
					)
					(width 0)
					(fill yes)
				)
			)
		)
		(pad "7" smd custom
			(at -2.4511 0.599948 90)
			(size 0.0508 0.0508)
			(layers "F.Cu" "F.Mask" "F.Paste")
			(net "SMB_VR_STBY_LVC3_SCL")
			(options
				(clearance outline)
				(anchor circle)
			)
			(primitives
				(gr_poly
					(pts
						(arc
							(start 0.254 -0.1016)
							(mid 0.3556 0)
							(end 0.254 0.1016)
						)
						(xy -0.3556 0.1016) (xy -0.3556 -0.1016)
					)
					(width 0)
					(fill yes)
				)
			)
		)
		(pad "8" smd custom
			(at -2.4511 0.999998 90)
			(size 0.0508 0.0508)
			(layers "F.Cu" "F.Mask" "F.Paste")
			(net "Net_284")
			(options
				(clearance outline)
				(anchor circle)
			)
			(primitives
				(gr_poly
					(pts
						(arc
							(start 0.254 -0.1016)
							(mid 0.3556 0)
							(end 0.254 0.1016)
						)
						(xy -0.3556 0.1016) (xy -0.3556 -0.1016)
					)
					(width 0)
					(fill yes)
				)
			)
		)
		(pad "9" smd custom
			(at -2.4511 1.400048 90)
			(size 0.0508 0.0508)
			(layers "F.Cu" "F.Mask" "F.Paste")
			(net "PWRGD_PVDDQ_DEF_R")
			(options
				(clearance outline)
				(anchor circle)
			)
			(primitives
				(gr_poly
					(pts
						(arc
							(start 0.254 -0.1016)
							(mid 0.3556 0)
							(end 0.254 0.1016)
						)
						(xy -0.3556 0.1016) (xy -0.3556 -0.1016)
					)
					(width 0)
					(fill yes)
				)
			)
		)
		(pad "10" smd custom
			(at -2.4511 1.800098 90)
			(size 0.0508 0.0508)
			(layers "F.Cu" "F.Mask" "F.Paste")
			(net "VR_PVDDQ_DEF_VREN")
			(options
				(clearance outline)
				(anchor circle)
			)
			(primitives
				(gr_poly
					(pts
						(arc
							(start 0.254 -0.1016)
							(mid 0.3556 0)
							(end 0.254 0.1016)
						)
						(xy -0.3556 0.1016) (xy -0.3556 -0.1016)
					)
					(width 0)
					(fill yes)
				)
			)
		)
		(pad "11" smd custom
			(at -1.800098 2.4511 90)
			(size 0.0508 0.0508)
			(layers "F.Cu" "F.Mask" "F.Paste")
			(net "IRQ_PVDDQ_DEF_VRHOT_LVT3_R_N")
			(options
				(clearance outline)
				(anchor circle)
			)
			(primitives
				(gr_poly
					(pts
						(arc
							(start -0.1016 -0.254)
							(mid 0 -0.3556)
							(end 0.1016 -0.254)
						)
						(xy 0.1016 0.3556) (xy -0.1016 0.3556)
					)
					(width 0)
					(fill yes)
				)
			)
		)
		(pad "12" smd custom
			(at -1.400048 2.4511 90)
			(size 0.0508 0.0508)
			(layers "F.Cu" "F.Mask" "F.Paste")
			(net "Net_230")
			(options
				(clearance outline)
				(anchor circle)
			)
			(primitives
				(gr_poly
					(pts
						(arc
							(start -0.1016 -0.254)
							(mid 0 -0.3556)
							(end 0.1016 -0.254)
						)
						(xy 0.1016 0.3556) (xy -0.1016 0.3556)
					)
					(width 0)
					(fill yes)
				)
			)
		)
		(pad "13" smd custom
			(at -0.999998 2.4511 90)
			(size 0.0508 0.0508)
			(layers "F.Cu" "F.Mask" "F.Paste")
			(net "PU_VR_PVDDQ_DEF_FAULT1")
			(options
				(clearance outline)
				(anchor circle)
			)
			(primitives
				(gr_poly
					(pts
						(arc
							(start -0.1016 -0.254)
							(mid 0 -0.3556)
							(end 0.1016 -0.254)
						)
						(xy 0.1016 0.3556) (xy -0.1016 0.3556)
					)
					(width 0)
					(fill yes)
				)
			)
		)
		(pad "14" smd custom
			(at -0.599948 2.4511 90)
			(size 0.0508 0.0508)
			(layers "F.Cu" "F.Mask" "F.Paste")
			(net "TP_PVDDQ_DEF_MP1")
			(options
				(clearance outline)
				(anchor circle)
			)
			(primitives
				(gr_poly
					(pts
						(arc
							(start -0.1016 -0.254)
							(mid 0 -0.3556)
							(end 0.1016 -0.254)
						)
						(xy 0.1016 0.3556) (xy -0.1016 0.3556)
					)
					(width 0)
					(fill yes)
				)
			)
		)
		(pad "15" smd custom
			(at -0.199898 2.4511 90)
			(size 0.0508 0.0508)
			(layers "F.Cu" "F.Mask" "F.Paste")
			(net "SVID_CLK_PVDDQ_DEF")
			(options
				(clearance outline)
				(anchor circle)
			)
			(primitives
				(gr_poly
					(pts
						(arc
							(start -0.1016 -0.254)
							(mid 0 -0.3556)
							(end 0.1016 -0.254)
						)
						(xy 0.1016 0.3556) (xy -0.1016 0.3556)
					)
					(width 0)
					(fill yes)
				)
			)
		)
		(pad "16" smd custom
			(at 0.199898 2.4511 90)
			(size 0.0508 0.0508)
			(layers "F.Cu" "F.Mask" "F.Paste")
			(net "SVID_VDIO_PVDDQ_DEF")
			(options
				(clearance outline)
				(anchor circle)
			)
			(primitives
				(gr_poly
					(pts
						(arc
							(start -0.1016 -0.254)
							(mid 0 -0.3556)
							(end 0.1016 -0.254)
						)
						(xy 0.1016 0.3556) (xy -0.1016 0.3556)
					)
					(width 0)
					(fill yes)
				)
			)
		)
		(pad "17" smd custom
			(at 0.599948 2.4511 90)
			(size 0.0508 0.0508)
			(layers "F.Cu" "F.Mask" "F.Paste")
			(net "SVID_ALERT_PVDDQ_DEF")
			(options
				(clearance outline)
				(anchor circle)
			)
			(primitives
				(gr_poly
					(pts
						(arc
							(start -0.1016 -0.254)
							(mid 0 -0.3556)
							(end 0.1016 -0.254)
						)
						(xy 0.1016 0.3556) (xy -0.1016 0.3556)
					)
					(width 0)
					(fill yes)
				)
			)
		)
	)
)
